# T6G (Grand Teton) — schematic netlist excerpt (pin names and nets, part order shuffled) for the footprints in the layout excerpt that follows; sources: Cadence DE-HDL packaged netlist, KiCad conversion of 04192023_DAF0TMB3IC0_F0TG_MB_C_brd_V02_OCP.brd

R4537  Q_RES  0 5% CHIP  pkg 0402LF  page 111 : A = FM_P2E_EN_N ; B = CLK_GEN2_GPU_FPGA_OE_OR_N
C3911  Q_CAP  22UF 4V 20% X6S  pkg C0402  page 72 : A = PVDDIO_P1 ; B = GND

(kicad_pcb
	(version 20260206)
	(generator "pcbnew")
	(generator_version "10.0")
	(general
		(thickness 1.6)
		(legacy_teardrops no)
	)
	(paper "A4")
	(title_block
		(title "04192023_DAF0TMB3IC0_F0TG_MB_C_brd_V02_OCP.brd")
		(comment 1 "Grand Teton / footprints 1092-1093 of 8354")
	)
	(layers
		(0 "F.Cu" signal "TOP")
		(4 "In1.Cu" signal "GND")
		(6 "In2.Cu" signal "IN1")
		(8 "In3.Cu" signal "GND1")
		(10 "In4.Cu" signal "IN2")
		(12 "In5.Cu" signal "GND2")
		(14 "In6.Cu" signal "IN3")
		(16 "In7.Cu" signal "GND3")
		(18 "In8.Cu" signal "VCC")
		(20 "In9.Cu" signal "VCC1")
		(22 "In10.Cu" signal "GND4")
		(24 "In11.Cu" signal "IN4")
		(26 "In12.Cu" signal "GND5")
		(28 "In13.Cu" signal "IN5")
		(30 "In14.Cu" signal "GND6")
		(32 "In15.Cu" signal "IN6")
		(34 "In16.Cu" signal "GND7")
		(2 "B.Cu" signal "BOTTOM")
		(9 "F.Adhes" user "F.Adhesive")
		(11 "B.Adhes" user "B.Adhesive")
		(13 "F.Paste" user "Package Geometry/Pastemask Top")
		(15 "B.Paste" user "Package Geometry/Pastemask Bottom")
		(5 "F.SilkS" user "Ref Des/Silkscreen Top")
		(7 "B.SilkS" user "Ref Des/Silkscreen Bottom")
		(1 "F.Mask" user "Board Geometry/Soldermask Top")
		(3 "B.Mask" user "Board Geometry/Soldermask Bottom")
		(17 "Dwgs.User" user "User.Drawings")
		(19 "Cmts.User" user "User.Comments")
		(21 "Eco1.User" user "User.Eco1")
		(23 "Eco2.User" user "User.Eco2")
		(25 "Edge.Cuts" user "Board Geometry/Outline")
		(27 "Margin" user)
		(31 "F.CrtYd" user "Package Geometry/Place Bound Top")
		(29 "B.CrtYd" user "Package Geometry/Place Bound Bottom")
		(35 "F.Fab" user "Ref Des/Assembly Top")
		(33 "B.Fab" user "Ref Des/Assembly Bottom")
	)
	(footprint ""
		(layer "F.Cu")
		(at 38.443662 -429.790098 90)
		(property "Reference" "R4537"
			(at 0 0 90)
			(layer "F.SilkS")
			(hide yes)
			(effects
				(font
					(size 1.27 1.27)
				)
			)
		)
		(property "Value" ""
			(at 0 0 90)
			(layer "F.Fab")
			(effects
				(font
					(size 1.27 1.27)
				)
			)
		)
		(duplicate_pad_numbers_are_jumpers no)
		(fp_line
			(start 0.7874 -0.4064)
			(end 0.7874 0.4064)
			(stroke
				(width 0.1524)
				(type default)
			)
			(layer "F.SilkS")
		)
		(fp_line
			(start -0.7874 -0.4064)
			(end 0.7874 -0.4064)
			(stroke
				(width 0.1524)
				(type default)
			)
			(layer "F.SilkS")
		)
		(fp_line
			(start 0.7874 0.4064)
			(end -0.7874 0.4064)
			(stroke
				(width 0.1524)
				(type default)
			)
			(layer "F.SilkS")
		)
		(fp_line
			(start -0.7874 0.4064)
			(end -0.7874 -0.4064)
			(stroke
				(width 0.1524)
				(type default)
			)
			(layer "F.SilkS")
		)
		(fp_line
			(start -0.12065 -0.305054)
			(end -0.12065 -0.2794)
			(stroke
				(width 0.1)
				(type default)
			)
			(layer "F.Fab")
		)
		(fp_line
			(start -0.67945 -0.305054)
			(end -0.12065 -0.305054)
			(stroke
				(width 0.1)
				(type default)
			)
			(layer "F.Fab")
		)
		(fp_line
			(start 0.67945 -0.3048)
			(end 0.67945 0.3048)
			(stroke
				(width 0.1)
				(type default)
			)
			(layer "F.Fab")
		)
		(fp_line
			(start 0.12065 -0.3048)
			(end 0.67945 -0.3048)
			(stroke
				(width 0.1)
				(type default)
			)
			(layer "F.Fab")
		)
		(fp_line
			(start 0.12065 -0.2794)
			(end 0.12065 -0.3048)
			(stroke
				(width 0.1)
				(type default)
			)
			(layer "F.Fab")
		)
		(fp_line
			(start -0.12065 -0.2794)
			(end 0.12065 -0.2794)
			(stroke
				(width 0.1)
				(type default)
			)
			(layer "F.Fab")
		)
		(fp_line
			(start 0.120396 0.2794)
			(end -0.12065 0.2794)
			(stroke
				(width 0.1)
				(type default)
			)
			(layer "F.Fab")
		)
		(fp_line
			(start -0.12065 0.2794)
			(end -0.12065 0.3048)
			(stroke
				(width 0.1)
				(type default)
			)
			(layer "F.Fab")
		)
		(fp_line
			(start 0.67945 0.3048)
			(end 0.120396 0.3048)
			(stroke
				(width 0.1)
				(type default)
			)
			(layer "F.Fab")
		)
		(fp_line
			(start 0.120396 0.3048)
			(end 0.120396 0.2794)
			(stroke
				(width 0.1)
				(type default)
			)
			(layer "F.Fab")
		)
		(fp_line
			(start -0.12065 0.3048)
			(end -0.67945 0.3048)
			(stroke
				(width 0.1)
				(type default)
			)
			(layer "F.Fab")
		)
		(fp_line
			(start -0.67945 0.3048)
			(end -0.67945 -0.305054)
			(stroke
				(width 0.1)
				(type default)
			)
			(layer "F.Fab")
		)
		(pad "1" smd circle
			(at -0.40005 0 90)
			(size 0 0)
			(layers "F.Cu" "F.Mask" "F.Paste")
			(net "FM_P2E_EN_N")
		)
		(pad "2" smd circle
			(at 0.40005 0 90)
			(size 0 0)
			(layers "F.Cu" "F.Mask" "F.Paste")
			(net "CLK_GEN2_GPU_FPGA_OE_OR_N")
		)
	)
	(footprint ""
		(layer "F.Cu")
		(at 105.960164 -261.255256)
		(property "Reference" "C3911"
			(at 0 0 0)
			(layer "F.SilkS")
			(hide yes)
			(effects
				(font
					(size 1.27 1.27)
				)
			)
		)
		(property "Value" ""
			(at 0 0 0)
			(layer "F.Fab")
			(effects
				(font
					(size 1.27 1.27)
				)
			)
		)
		(duplicate_pad_numbers_are_jumpers no)
		(fp_line
			(start -0.7874 -0.4064)
			(end 0.7874 -0.4064)
			(stroke
				(width 0.1524)
				(type default)
			)
			(layer "F.SilkS")
		)
		(fp_line
			(start -0.7874 0.4064)
			(end -0.7874 -0.4064)
			(stroke
				(width 0.1524)
				(type default)
			)
			(layer "F.SilkS")
		)
		(fp_line
			(start 0.7874 -0.4064)
			(end 0.7874 0.4064)
			(stroke
				(width 0.1524)
				(type default)
			)
			(layer "F.SilkS")
		)
		(fp_line
			(start 0.7874 0.4064)
			(end -0.7874 0.4064)
			(stroke
				(width 0.1524)
				(type default)
			)
			(layer "F.SilkS")
		)
		(fp_line
			(start -0.67945 -0.305054)
			(end -0.12065 -0.305054)
			(stroke
				(width 0.1)
				(type default)
			)
			(layer "F.Fab")
		)
		(fp_line
			(start -0.67945 0.3048)
			(end -0.67945 -0.305054)
			(stroke
				(width 0.1)
				(type default)
			)
			(layer "F.Fab")
		)
		(fp_line
			(start -0.12065 -0.305054)
			(end -0.12065 -0.2794)
			(stroke
				(width 0.1)
				(type default)
			)
			(layer "F.Fab")
		)
		(fp_line
			(start -0.12065 -0.2794)
			(end 0.12065 -0.2794)
			(stroke
				(width 0.1)
				(type default)
			)
			(layer "F.Fab")
		)
		(fp_line
			(start -0.12065 0.2794)
			(end -0.12065 0.3048)
			(stroke
				(width 0.1)
				(type default)
			)
			(layer "F.Fab")
		)
		(fp_line
			(start -0.12065 0.3048)
			(end -0.67945 0.3048)
			(stroke
				(width 0.1)
				(type default)
			)
			(layer "F.Fab")
		)
		(fp_line
			(start 0.120396 0.2794)
			(end -0.12065 0.2794)
			(stroke
				(width 0.1)
				(type default)
			)
			(layer "F.Fab")
		)
		(fp_line
			(start 0.120396 0.3048)
			(end 0.120396 0.2794)
			(stroke
				(width 0.1)
				(type default)
			)
			(layer "F.Fab")
		)
		(fp_line
			(start 0.12065 -0.3048)
			(end 0.67945 -0.3048)
			(stroke
				(width 0.1)
				(type default)
			)
			(layer "F.Fab")
		)
		(fp_line
			(start 0.12065 -0.2794)
			(end 0.12065 -0.3048)
			(stroke
				(width 0.1)
				(type default)
			)
			(layer "F.Fab")
		)
		(fp_line
			(start 0.67945 -0.3048)
			(end 0.67945 0.3048)
			(stroke
				(width 0.1)
				(type default)
			)
			(layer "F.Fab")
		)
		(fp_line
			(start 0.67945 0.3048)
			(end 0.120396 0.3048)
			(stroke
				(width 0.1)
				(type default)
			)
			(layer "F.Fab")
		)
		(pad "1" smd circle
			(at -0.40005 0)
			(size 0 0)
			(layers "F.Cu" "F.Mask" "F.Paste")
			(net "PVDDIO_P1")
		)
		(pad "2" smd circle
			(at 0.40005 0)
			(size 0 0)
			(layers "F.Cu" "F.Mask" "F.Paste")
			(net "GND")
		)
	)
)
